(kicad_pcb
	(version 20260206)
	(generator "pcbnew")
	(generator_version "10.0")
	(general
		(thickness 1.6)
		(legacy_teardrops no)
	)
	(paper "A4")
	(title_block
		(title "01162023_DA0F0TEBIF0_F0T_Expander_BD_F_brd_V02_OCP.brd")
		(comment 1 "Grand Teton / footprints 2566-2572 of 9728")
	)
	(layers
		(0 "F.Cu" signal "TOP")
		(4 "In1.Cu" signal "GND")
		(6 "In2.Cu" signal "VCC")
		(8 "In3.Cu" signal "VCC1")
		(10 "In4.Cu" signal "GND1")
		(12 "In5.Cu" signal "IN1")
		(14 "In6.Cu" signal "GND2")
		(16 "In7.Cu" signal "IN2")
		(18 "In8.Cu" signal "GND3")
		(20 "In9.Cu" signal "IN3")
		(22 "In10.Cu" signal "GND4")
		(24 "In11.Cu" signal "IN4")
		(26 "In12.Cu" signal "GND5")
		(28 "In13.Cu" signal "IN5")
		(30 "In14.Cu" signal "GND6")
		(32 "In15.Cu" signal "IN6")
		(34 "In16.Cu" signal "GND7")
		(2 "B.Cu" signal "BOTTOM")
		(9 "F.Adhes" user "F.Adhesive")
		(11 "B.Adhes" user "B.Adhesive")
		(13 "F.Paste" user "Package Geometry/Pastemask Top")
		(15 "B.Paste" user "Package Geometry/Pastemask Bottom")
		(5 "F.SilkS" user "Ref Des/Silkscreen Top")
		(7 "B.SilkS" user "Ref Des/Silkscreen Bottom")
		(1 "F.Mask" user "Board Geometry/Soldermask Top")
		(3 "B.Mask" user "Board Geometry/Soldermask Bottom")
		(17 "Dwgs.User" user "User.Drawings")
		(19 "Cmts.User" user "User.Comments")
		(21 "Eco1.User" user "User.Eco1")
		(23 "Eco2.User" user "User.Eco2")
		(25 "Edge.Cuts" user "Board Geometry/Outline")
		(27 "Margin" user)
		(31 "F.CrtYd" user "Package Geometry/Place Bound Top")
		(29 "B.CrtYd" user "Package Geometry/Place Bound Bottom")
		(35 "F.Fab" user "Ref Des/Assembly Top")
		(33 "B.Fab" user "Ref Des/Assembly Bottom")
	)
	(footprint ""
		(layer "F.Cu")
		(at 30.081982 -280.189432 180)
		(property "Reference" "C3073"
			(at 0 0 180)
			(layer "F.SilkS")
			(hide yes)
			(effects
				(font
					(size 1.27 1.27)
				)
			)
		)
		(property "Value" ""
			(at 0 0 180)
			(layer "F.Fab")
			(effects
				(font
					(size 1.27 1.27)
				)
			)
		)
		(duplicate_pad_numbers_are_jumpers no)
		(fp_line
			(start 1.2954 0.5842)
			(end -1.2954 0.5842)
			(stroke
				(width 0.1524)
				(type default)
			)
			(layer "F.SilkS")
		)
		(fp_line
			(start 1.2954 -0.5842)
			(end 1.2954 0.5842)
			(stroke
				(width 0.1524)
				(type default)
			)
			(layer "F.SilkS")
		)
		(fp_line
			(start -1.2954 0.5842)
			(end -1.2954 -0.5842)
			(stroke
				(width 0.1524)
				(type default)
			)
			(layer "F.SilkS")
		)
		(fp_line
			(start -1.2954 -0.5842)
			(end 1.2954 -0.5842)
			(stroke
				(width 0.1524)
				(type default)
			)
			(layer "F.SilkS")
		)
		(fp_line
			(start 1.1938 0.4064)
			(end 0.8636 0.4064)
			(stroke
				(width 0.1)
				(type default)
			)
			(layer "F.Fab")
		)
		(fp_line
			(start 1.1938 -0.4064)
			(end 1.1938 0.4064)
			(stroke
				(width 0.1)
				(type default)
			)
			(layer "F.Fab")
		)
		(fp_line
			(start 0.8636 0.4572)
			(end -0.8636 0.4572)
			(stroke
				(width 0.1)
				(type default)
			)
			(layer "F.Fab")
		)
		(fp_line
			(start 0.8636 0.4064)
			(end 0.8636 0.4572)
			(stroke
				(width 0.1)
				(type default)
			)
			(layer "F.Fab")
		)
		(fp_line
			(start 0.8636 -0.4064)
			(end 1.1938 -0.4064)
			(stroke
				(width 0.1)
				(type default)
			)
			(layer "F.Fab")
		)
		(fp_line
			(start 0.8636 -0.4572)
			(end 0.8636 -0.4064)
			(stroke
				(width 0.1)
				(type default)
			)
			(layer "F.Fab")
		)
		(fp_line
			(start -0.8636 0.4572)
			(end -0.8636 0.4064)
			(stroke
				(width 0.1)
				(type default)
			)
			(layer "F.Fab")
		)
		(fp_line
			(start -0.8636 0.4064)
			(end -1.1938 0.4064)
			(stroke
				(width 0.1)
				(type default)
			)
			(layer "F.Fab")
		)
		(fp_line
			(start -0.8636 -0.4064)
			(end -0.8636 -0.4572)
			(stroke
				(width 0.1)
				(type default)
			)
			(layer "F.Fab")
		)
		(fp_line
			(start -0.8636 -0.4572)
			(end 0.8636 -0.4572)
			(stroke
				(width 0.1)
				(type default)
			)
			(layer "F.Fab")
		)
		(fp_line
			(start -1.1938 0.4064)
			(end -1.1938 -0.4064)
			(stroke
				(width 0.1)
				(type default)
			)
			(layer "F.Fab")
		)
		(fp_line
			(start -1.1938 -0.4064)
			(end -0.8636 -0.4064)
			(stroke
				(width 0.1)
				(type default)
			)
			(layer "F.Fab")
		)
		(pad "1" smd rect
			(at -0.7366 0 90)
			(size 0.7112 0.8128)
			(layers "F.Cu" "F.Mask" "F.Paste")
			(net "SYSPLL_VDDA18_PEX0_R")
		)
		(pad "2" smd rect
			(at 0.7366 0 90)
			(size 0.7112 0.8128)
			(layers "F.Cu" "F.Mask" "F.Paste")
			(net "GND")
		)
	)
	(footprint ""
		(layer "F.Cu")
		(at 230.620062 -254.454914 -90)
		(property "Reference" "C4286"
			(at 0 0 270)
			(layer "F.SilkS")
			(hide yes)
			(effects
				(font
					(size 1.27 1.27)
				)
			)
		)
		(property "Value" ""
			(at 0 0 270)
			(layer "F.Fab")
			(effects
				(font
					(size 1.27 1.27)
				)
			)
		)
		(duplicate_pad_numbers_are_jumpers no)
		(fp_line
			(start -1.524 0.762)
			(end -1.524 -0.762)
			(stroke
				(width 0.1524)
				(type default)
			)
			(layer "F.SilkS")
		)
		(fp_line
			(start 1.524 0.762)
			(end -1.524 0.762)
			(stroke
				(width 0.1524)
				(type default)
			)
			(layer "F.SilkS")
		)
		(fp_line
			(start -1.524 -0.762)
			(end 1.524 -0.762)
			(stroke
				(width 0.1524)
				(type default)
			)
			(layer "F.SilkS")
		)
		(fp_line
			(start 1.524 -0.762)
			(end 1.524 0.762)
			(stroke
				(width 0.1524)
				(type default)
			)
			(layer "F.SilkS")
		)
		(fp_line
			(start -1.1049 0.724916)
			(end 1.1049 0.724916)
			(stroke
				(width 0.1)
				(type default)
			)
			(layer "F.Fab")
		)
		(fp_line
			(start 1.1049 0.724916)
			(end 1.1049 -0.724916)
			(stroke
				(width 0.1)
				(type default)
			)
			(layer "F.Fab")
		)
		(fp_line
			(start -1.1049 -0.724916)
			(end -1.1049 0.724916)
			(stroke
				(width 0.1)
				(type default)
			)
			(layer "F.Fab")
		)
		(fp_line
			(start 1.1049 -0.724916)
			(end -1.1049 -0.724916)
			(stroke
				(width 0.1)
				(type default)
			)
			(layer "F.Fab")
		)
		(pad "1" smd rect
			(at -0.889 0 90)
			(size 1.016 1.27)
			(layers "F.Cu" "F.Mask" "F.Paste")
			(net "P1V25_SERDES_VDDPLL_PEX1_C4")
		)
		(pad "2" smd rect
			(at 0.889 0 90)
			(size 1.016 1.27)
			(layers "F.Cu" "F.Mask" "F.Paste")
			(net "GND")
		)
		(zone
			(layer "F.Cu")
			(hatch none 0.5)
			(connect_pads
				(clearance 0)
			)
			(min_thickness 0.25)
			(keepout
				(tracks not_allowed)
				(vias allowed)
				(pads allowed)
				(copperpour not_allowed)
				(footprints allowed)
			)
			(placement
				(enabled no)
				(sheetname "")
			)
			(fill
				(thermal_gap 0.5)
				(thermal_bridge_width 0.5)
				(island_removal_mode 0)
			)
			(polygon
				(pts
					(xy 231.344978 -254.785114) (xy 229.895146 -254.785114) (xy 229.895146 -254.124714) (xy 231.344978 -254.124714)
				)
			)
		)
	)
	(footprint ""
		(layer "F.Cu")
		(at 407.009092 -27.04973 180)
		(property "Reference" "C2777"
			(at 0 0 180)
			(layer "F.SilkS")
			(hide yes)
			(effects
				(font
					(size 1.27 1.27)
				)
			)
		)
		(property "Value" ""
			(at 0 0 180)
			(layer "F.Fab")
			(effects
				(font
					(size 1.27 1.27)
				)
			)
		)
		(duplicate_pad_numbers_are_jumpers no)
		(fp_line
			(start 0.7874 0.4064)
			(end -0.7874 0.4064)
			(stroke
				(width 0.1524)
				(type default)
			)
			(layer "F.SilkS")
		)
		(fp_line
			(start 0.7874 -0.4064)
			(end 0.7874 0.4064)
			(stroke
				(width 0.1524)
				(type default)
			)
			(layer "F.SilkS")
		)
		(fp_line
			(start -0.7874 0.4064)
			(end -0.7874 -0.4064)
			(stroke
				(width 0.1524)
				(type default)
			)
			(layer "F.SilkS")
		)
		(fp_line
			(start -0.7874 -0.4064)
			(end 0.7874 -0.4064)
			(stroke
				(width 0.1524)
				(type default)
			)
			(layer "F.SilkS")
		)
		(fp_line
			(start 0.67945 0.3048)
			(end 0.120396 0.3048)
			(stroke
				(width 0.1)
				(type default)
			)
			(layer "F.Fab")
		)
		(fp_line
			(start 0.67945 -0.3048)
			(end 0.67945 0.3048)
			(stroke
				(width 0.1)
				(type default)
			)
			(layer "F.Fab")
		)
		(fp_line
			(start 0.12065 -0.2794)
			(end 0.12065 -0.3048)
			(stroke
				(width 0.1)
				(type default)
			)
			(layer "F.Fab")
		)
		(fp_line
			(start 0.12065 -0.3048)
			(end 0.67945 -0.3048)
			(stroke
				(width 0.1)
				(type default)
			)
			(layer "F.Fab")
		)
		(fp_line
			(start 0.120396 0.3048)
			(end 0.120396 0.2794)
			(stroke
				(width 0.1)
				(type default)
			)
			(layer "F.Fab")
		)
		(fp_line
			(start 0.120396 0.2794)
			(end -0.12065 0.2794)
			(stroke
				(width 0.1)
				(type default)
			)
			(layer "F.Fab")
		)
		(fp_line
			(start -0.12065 0.3048)
			(end -0.67945 0.3048)
			(stroke
				(width 0.1)
				(type default)
			)
			(layer "F.Fab")
		)
		(fp_line
			(start -0.12065 0.2794)
			(end -0.12065 0.3048)
			(stroke
				(width 0.1)
				(type default)
			)
			(layer "F.Fab")
		)
		(fp_line
			(start -0.12065 -0.2794)
			(end 0.12065 -0.2794)
			(stroke
				(width 0.1)
				(type default)
			)
			(layer "F.Fab")
		)
		(fp_line
			(start -0.12065 -0.305054)
			(end -0.12065 -0.2794)
			(stroke
				(width 0.1)
				(type default)
			)
			(layer "F.Fab")
		)
		(fp_line
			(start -0.67945 0.3048)
			(end -0.67945 -0.305054)
			(stroke
				(width 0.1)
				(type default)
			)
			(layer "F.Fab")
		)
		(fp_line
			(start -0.67945 -0.305054)
			(end -0.12065 -0.305054)
			(stroke
				(width 0.1)
				(type default)
			)
			(layer "F.Fab")
		)
		(pad "1" smd circle
			(at -0.40005 0 180)
			(size 0 0)
			(layers "F.Cu" "F.Mask" "F.Paste")
			(net "PRSNT_SSD14_R_N")
		)
		(pad "2" smd circle
			(at 0.40005 0 180)
			(size 0 0)
			(layers "F.Cu" "F.Mask" "F.Paste")
			(net "GND")
		)
	)
	(footprint ""
		(layer "F.Cu")
		(at 136.534652 -34.546286 180)
		(property "Reference" "C276"
			(at 0 0 180)
			(layer "F.SilkS")
			(hide yes)
			(effects
				(font
					(size 1.27 1.27)
				)
			)
		)
		(property "Value" ""
			(at 0 0 180)
			(layer "F.Fab")
			(effects
				(font
					(size 1.27 1.27)
				)
			)
		)
		(duplicate_pad_numbers_are_jumpers no)
		(fp_line
			(start 0.299974 0.150114)
			(end -0.299974 0.150114)
			(stroke
				(width 0.1)
				(type default)
			)
			(layer "F.Fab")
		)
		(fp_line
			(start 0.299974 -0.150114)
			(end 0.299974 0.150114)
			(stroke
				(width 0.1)
				(type default)
			)
			(layer "F.Fab")
		)
		(fp_line
			(start -0.299974 0.150114)
			(end -0.299974 -0.150114)
			(stroke
				(width 0.1)
				(type default)
			)
			(layer "F.Fab")
		)
		(fp_line
			(start -0.299974 -0.150114)
			(end 0.299974 -0.150114)
			(stroke
				(width 0.1)
				(type default)
			)
			(layer "F.Fab")
		)
		(pad "1" smd rect
			(at -0.2667 0 180)
			(size 0.3048 0.381)
			(layers "F.Cu" "F.Mask" "F.Paste")
			(net "P5E_PEX1_STN2_TX_DP<47>")
		)
		(pad "2" smd rect
			(at 0.2667 0 180)
			(size 0.3048 0.381)
			(layers "F.Cu" "F.Mask" "F.Paste")
			(net "P5E_PEX1_STN2_TX_C_DP<47>")
		)
	)
	(footprint ""
		(layer "F.Cu")
		(at 223.706944 -98.36912 -90)
		(property "Reference" "R4454"
			(at 0 0 270)
			(layer "F.SilkS")
			(hide yes)
			(effects
				(font
					(size 1.27 1.27)
				)
			)
		)
		(property "Value" ""
			(at 0 0 270)
			(layer "F.Fab")
			(effects
				(font
					(size 1.27 1.27)
				)
			)
		)
		(duplicate_pad_numbers_are_jumpers no)
		(fp_line
			(start -0.7874 0.4064)
			(end -0.7874 -0.4064)
			(stroke
				(width 0.1524)
				(type default)
			)
			(layer "F.SilkS")
		)
		(fp_line
			(start 0.7874 0.4064)
			(end -0.7874 0.4064)
			(stroke
				(width 0.1524)
				(type default)
			)
			(layer "F.SilkS")
		)
		(fp_line
			(start -0.7874 -0.4064)
			(end 0.7874 -0.4064)
			(stroke
				(width 0.1524)
				(type default)
			)
			(layer "F.SilkS")
		)
		(fp_line
			(start 0.7874 -0.4064)
			(end 0.7874 0.4064)
			(stroke
				(width 0.1524)
				(type default)
			)
			(layer "F.SilkS")
		)
		(fp_line
			(start -0.67945 0.3048)
			(end -0.67945 -0.305054)
			(stroke
				(width 0.1)
				(type default)
			)
			(layer "F.Fab")
		)
		(fp_line
			(start -0.12065 0.3048)
			(end -0.67945 0.3048)
			(stroke
				(width 0.1)
				(type default)
			)
			(layer "F.Fab")
		)
		(fp_line
			(start 0.120396 0.3048)
			(end 0.120396 0.2794)
			(stroke
				(width 0.1)
				(type default)
			)
			(layer "F.Fab")
		)
		(fp_line
			(start 0.67945 0.3048)
			(end 0.120396 0.3048)
			(stroke
				(width 0.1)
				(type default)
			)
			(layer "F.Fab")
		)
		(fp_line
			(start -0.12065 0.2794)
			(end -0.12065 0.3048)
			(stroke
				(width 0.1)
				(type default)
			)
			(layer "F.Fab")
		)
		(fp_line
			(start 0.120396 0.2794)
			(end -0.12065 0.2794)
			(stroke
				(width 0.1)
				(type default)
			)
			(layer "F.Fab")
		)
		(fp_line
			(start -0.12065 -0.2794)
			(end 0.12065 -0.2794)
			(stroke
				(width 0.1)
				(type default)
			)
			(layer "F.Fab")
		)
		(fp_line
			(start 0.12065 -0.2794)
			(end 0.12065 -0.3048)
			(stroke
				(width 0.1)
				(type default)
			)
			(layer "F.Fab")
		)
		(fp_line
			(start 0.12065 -0.3048)
			(end 0.67945 -0.3048)
			(stroke
				(width 0.1)
				(type default)
			)
			(layer "F.Fab")
		)
		(fp_line
			(start 0.67945 -0.3048)
			(end 0.67945 0.3048)
			(stroke
				(width 0.1)
				(type default)
			)
			(layer "F.Fab")
		)
		(fp_line
			(start -0.67945 -0.305054)
			(end -0.12065 -0.305054)
			(stroke
				(width 0.1)
				(type default)
			)
			(layer "F.Fab")
		)
		(fp_line
			(start -0.12065 -0.305054)
			(end -0.12065 -0.2794)
			(stroke
				(width 0.1)
				(type default)
			)
			(layer "F.Fab")
		)
		(pad "1" smd circle
			(at -0.40005 0 270)
			(size 0 0)
			(layers "F.Cu" "F.Mask" "F.Paste")
			(net "PWRGD_P12V_NIC3")
		)
		(pad "2" smd circle
			(at 0.40005 0 270)
			(size 0 0)
			(layers "F.Cu" "F.Mask" "F.Paste")
			(net "PWRGD_P12V_NIC3_R")
		)
	)
	(footprint ""
		(layer "F.Cu")
		(at 173.047406 -36.686998 90)
		(property "Reference" "C3665"
			(at 0 0 90)
			(layer "F.SilkS")
			(hide yes)
			(effects
				(font
					(size 1.27 1.27)
				)
			)
		)
		(property "Value" ""
			(at 0 0 90)
			(layer "F.Fab")
			(effects
				(font
					(size 1.27 1.27)
				)
			)
		)
		(duplicate_pad_numbers_are_jumpers no)
		(fp_line
			(start 0.7874 -0.4064)
			(end 0.7874 0.4064)
			(stroke
				(width 0.1524)
				(type default)
			)
			(layer "F.SilkS")
		)
		(fp_line
			(start -0.7874 -0.4064)
			(end 0.7874 -0.4064)
			(stroke
				(width 0.1524)
				(type default)
			)
			(layer "F.SilkS")
		)
		(fp_line
			(start 0.7874 0.4064)
			(end -0.7874 0.4064)
			(stroke
				(width 0.1524)
				(type default)
			)
			(layer "F.SilkS")
		)
		(fp_line
			(start -0.7874 0.4064)
			(end -0.7874 -0.4064)
			(stroke
				(width 0.1524)
				(type default)
			)
			(layer "F.SilkS")
		)
		(fp_line
			(start -0.12065 -0.305054)
			(end -0.12065 -0.2794)
			(stroke
				(width 0.1)
				(type default)
			)
			(layer "F.Fab")
		)
		(fp_line
			(start -0.67945 -0.305054)
			(end -0.12065 -0.305054)
			(stroke
				(width 0.1)
				(type default)
			)
			(layer "F.Fab")
		)
		(fp_line
			(start 0.67945 -0.3048)
			(end 0.67945 0.3048)
			(stroke
				(width 0.1)
				(type default)
			)
			(layer "F.Fab")
		)
		(fp_line
			(start 0.12065 -0.3048)
			(end 0.67945 -0.3048)
			(stroke
				(width 0.1)
				(type default)
			)
			(layer "F.Fab")
		)
		(fp_line
			(start 0.12065 -0.2794)
			(end 0.12065 -0.3048)
			(stroke
				(width 0.1)
				(type default)
			)
			(layer "F.Fab")
		)
		(fp_line
			(start -0.12065 -0.2794)
			(end 0.12065 -0.2794)
			(stroke
				(width 0.1)
				(type default)
			)
			(layer "F.Fab")
		)
		(fp_line
			(start 0.120396 0.2794)
			(end -0.12065 0.2794)
			(stroke
				(width 0.1)
				(type default)
			)
			(layer "F.Fab")
		)
		(fp_line
			(start -0.12065 0.2794)
			(end -0.12065 0.3048)
			(stroke
				(width 0.1)
				(type default)
			)
			(layer "F.Fab")
		)
		(fp_line
			(start 0.67945 0.3048)
			(end 0.120396 0.3048)
			(stroke
				(width 0.1)
				(type default)
			)
			(layer "F.Fab")
		)
		(fp_line
			(start 0.120396 0.3048)
			(end 0.120396 0.2794)
			(stroke
				(width 0.1)
				(type default)
			)
			(layer "F.Fab")
		)
		(fp_line
			(start -0.12065 0.3048)
			(end -0.67945 0.3048)
			(stroke
				(width 0.1)
				(type default)
			)
			(layer "F.Fab")
		)
		(fp_line
			(start -0.67945 0.3048)
			(end -0.67945 -0.305054)
			(stroke
				(width 0.1)
				(type default)
			)
			(layer "F.Fab")
		)
		(pad "1" smd circle
			(at -0.40005 0 90)
			(size 0 0)
			(layers "F.Cu" "F.Mask" "F.Paste")
			(net "P3V3_AUX")
		)
		(pad "2" smd circle
			(at 0.40005 0 90)
			(size 0 0)
			(layers "F.Cu" "F.Mask" "F.Paste")
			(net "GND")
		)
	)
	(footprint ""
		(layer "F.Cu")
		(at 367.558066 -72.766682 90)
		(property "Reference" "PC880"
			(at 0 0 90)
			(layer "F.SilkS")
			(hide yes)
			(effects
				(font
					(size 1.27 1.27)
				)
			)
		)
		(property "Value" ""
			(at 0 0 90)
			(layer "F.Fab")
			(effects
				(font
					(size 1.27 1.27)
				)
			)
		)
		(duplicate_pad_numbers_are_jumpers no)
		(fp_line
			(start 0.7874 -0.4064)
			(end 0.7874 0.4064)
			(stroke
				(width 0.1524)
				(type default)
			)
			(layer "F.SilkS")
		)
		(fp_line
			(start -0.7874 -0.4064)
			(end 0.7874 -0.4064)
			(stroke
				(width 0.1524)
				(type default)
			)
			(layer "F.SilkS")
		)
		(fp_line
			(start 0.7874 0.4064)
			(end -0.7874 0.4064)
			(stroke
				(width 0.1524)
				(type default)
			)
			(layer "F.SilkS")
		)
		(fp_line
			(start -0.7874 0.4064)
			(end -0.7874 -0.4064)
			(stroke
				(width 0.1524)
				(type default)
			)
			(layer "F.SilkS")
		)
		(fp_line
			(start -0.12065 -0.305054)
			(end -0.12065 -0.2794)
			(stroke
				(width 0.1)
				(type default)
			)
			(layer "F.Fab")
		)
		(fp_line
			(start -0.67945 -0.305054)
			(end -0.12065 -0.305054)
			(stroke
				(width 0.1)
				(type default)
			)
			(layer "F.Fab")
		)
		(fp_line
			(start 0.67945 -0.3048)
			(end 0.67945 0.3048)
			(stroke
				(width 0.1)
				(type default)
			)
			(layer "F.Fab")
		)
		(fp_line
			(start 0.12065 -0.3048)
			(end 0.67945 -0.3048)
			(stroke
				(width 0.1)
				(type default)
			)
			(layer "F.Fab")
		)
		(fp_line
			(start 0.12065 -0.2794)
			(end 0.12065 -0.3048)
			(stroke
				(width 0.1)
				(type default)
			)
			(layer "F.Fab")
		)
		(fp_line
			(start -0.12065 -0.2794)
			(end 0.12065 -0.2794)
			(stroke
				(width 0.1)
				(type default)
			)
			(layer "F.Fab")
		)
		(fp_line
			(start 0.120396 0.2794)
			(end -0.12065 0.2794)
			(stroke
				(width 0.1)
				(type default)
			)
			(layer "F.Fab")
		)
		(fp_line
			(start -0.12065 0.2794)
			(end -0.12065 0.3048)
			(stroke
				(width 0.1)
				(type default)
			)
			(layer "F.Fab")
		)
		(fp_line
			(start 0.67945 0.3048)
			(end 0.120396 0.3048)
			(stroke
				(width 0.1)
				(type default)
			)
			(layer "F.Fab")
		)
		(fp_line
			(start 0.120396 0.3048)
			(end 0.120396 0.2794)
			(stroke
				(width 0.1)
				(type default)
			)
			(layer "F.Fab")
		)
		(fp_line
			(start -0.12065 0.3048)
			(end -0.67945 0.3048)
			(stroke
				(width 0.1)
				(type default)
			)
			(layer "F.Fab")
		)
		(fp_line
			(start -0.67945 0.3048)
			(end -0.67945 -0.305054)
			(stroke
				(width 0.1)
				(type default)
			)
			(layer "F.Fab")
		)
		(pad "1" smd circle
			(at -0.40005 0 90)
			(size 0 0)
			(layers "F.Cu" "F.Mask" "F.Paste")
			(net "P12V_SSD12_CO_MODE")
		)
		(pad "2" smd circle
			(at 0.40005 0 90)
			(size 0 0)
			(layers "F.Cu" "F.Mask" "F.Paste")
			(net "GND")
		)
	)
)
